# T6G (Grand Teton) — schematic netlist excerpt (pin names and nets, part order shuffled) for the footprints in the layout excerpt that follows; sources: Cadence DE-HDL packaged netlist, KiCad conversion of 04192023_DAF0TMB3IC0_F0TG_MB_C_brd_V02_OCP.brd

PC259  Q_CAP  220PF 50V 10% X7R  pkg 0402  page 209 : A = PVDD18_S5_P0_FB ; B = PVDD18_S5_P0_FB_RC
R2625  Q_RES  49.9 1% CHIP  pkg 0402LF  page 267 : A = P12V_HSC_TEMP_R ; B = P12V_HSC_TEMP_D+

(kicad_pcb
	(version 20260206)
	(generator "pcbnew")
	(generator_version "10.0")
	(general
		(thickness 1.6)
		(legacy_teardrops no)
	)
	(paper "A4")
	(title_block
		(title "04192023_DAF0TMB3IC0_F0TG_MB_C_brd_V02_OCP.brd")
		(comment 1 "Grand Teton / footprints 731-732 of 8354")
	)
	(layers
		(0 "F.Cu" signal "TOP")
		(4 "In1.Cu" signal "GND")
		(6 "In2.Cu" signal "IN1")
		(8 "In3.Cu" signal "GND1")
		(10 "In4.Cu" signal "IN2")
		(12 "In5.Cu" signal "GND2")
		(14 "In6.Cu" signal "IN3")
		(16 "In7.Cu" signal "GND3")
		(18 "In8.Cu" signal "VCC")
		(20 "In9.Cu" signal "VCC1")
		(22 "In10.Cu" signal "GND4")
		(24 "In11.Cu" signal "IN4")
		(26 "In12.Cu" signal "GND5")
		(28 "In13.Cu" signal "IN5")
		(30 "In14.Cu" signal "GND6")
		(32 "In15.Cu" signal "IN6")
		(34 "In16.Cu" signal "GND7")
		(2 "B.Cu" signal "BOTTOM")
		(9 "F.Adhes" user "F.Adhesive")
		(11 "B.Adhes" user "B.Adhesive")
		(13 "F.Paste" user "Package Geometry/Pastemask Top")
		(15 "B.Paste" user "Package Geometry/Pastemask Bottom")
		(5 "F.SilkS" user "Ref Des/Silkscreen Top")
		(7 "B.SilkS" user "Ref Des/Silkscreen Bottom")
		(1 "F.Mask" user "Board Geometry/Soldermask Top")
		(3 "B.Mask" user "Board Geometry/Soldermask Bottom")
		(17 "Dwgs.User" user "User.Drawings")
		(19 "Cmts.User" user "User.Comments")
		(21 "Eco1.User" user "User.Eco1")
		(23 "Eco2.User" user "User.Eco2")
		(25 "Edge.Cuts" user "Board Geometry/Outline")
		(27 "Margin" user)
		(31 "F.CrtYd" user "Package Geometry/Place Bound Top")
		(29 "B.CrtYd" user "Package Geometry/Place Bound Bottom")
		(35 "F.Fab" user "Ref Des/Assembly Top")
		(33 "B.Fab" user "Ref Des/Assembly Bottom")
	)
	(footprint ""
		(layer "F.Cu")
		(at 329.282044 -138.893042 90)
		(property "Reference" "PC259"
			(at 0 0 90)
			(layer "F.SilkS")
			(hide yes)
			(effects
				(font
					(size 1.27 1.27)
				)
			)
		)
		(property "Value" ""
			(at 0 0 90)
			(layer "F.Fab")
			(effects
				(font
					(size 1.27 1.27)
				)
			)
		)
		(duplicate_pad_numbers_are_jumpers no)
		(fp_line
			(start 0.7874 -0.4064)
			(end 0.7874 0.4064)
			(stroke
				(width 0.1524)
				(type default)
			)
			(layer "F.SilkS")
		)
		(fp_line
			(start -0.7874 -0.4064)
			(end 0.7874 -0.4064)
			(stroke
				(width 0.1524)
				(type default)
			)
			(layer "F.SilkS")
		)
		(fp_line
			(start 0.7874 0.4064)
			(end -0.7874 0.4064)
			(stroke
				(width 0.1524)
				(type default)
			)
			(layer "F.SilkS")
		)
		(fp_line
			(start -0.7874 0.4064)
			(end -0.7874 -0.4064)
			(stroke
				(width 0.1524)
				(type default)
			)
			(layer "F.SilkS")
		)
		(fp_line
			(start -0.12065 -0.305054)
			(end -0.12065 -0.2794)
			(stroke
				(width 0.1)
				(type default)
			)
			(layer "F.Fab")
		)
		(fp_line
			(start -0.67945 -0.305054)
			(end -0.12065 -0.305054)
			(stroke
				(width 0.1)
				(type default)
			)
			(layer "F.Fab")
		)
		(fp_line
			(start 0.67945 -0.3048)
			(end 0.67945 0.3048)
			(stroke
				(width 0.1)
				(type default)
			)
			(layer "F.Fab")
		)
		(fp_line
			(start 0.12065 -0.3048)
			(end 0.67945 -0.3048)
			(stroke
				(width 0.1)
				(type default)
			)
			(layer "F.Fab")
		)
		(fp_line
			(start 0.12065 -0.2794)
			(end 0.12065 -0.3048)
			(stroke
				(width 0.1)
				(type default)
			)
			(layer "F.Fab")
		)
		(fp_line
			(start -0.12065 -0.2794)
			(end 0.12065 -0.2794)
			(stroke
				(width 0.1)
				(type default)
			)
			(layer "F.Fab")
		)
		(fp_line
			(start 0.120396 0.2794)
			(end -0.12065 0.2794)
			(stroke
				(width 0.1)
				(type default)
			)
			(layer "F.Fab")
		)
		(fp_line
			(start -0.12065 0.2794)
			(end -0.12065 0.3048)
			(stroke
				(width 0.1)
				(type default)
			)
			(layer "F.Fab")
		)
		(fp_line
			(start 0.67945 0.3048)
			(end 0.120396 0.3048)
			(stroke
				(width 0.1)
				(type default)
			)
			(layer "F.Fab")
		)
		(fp_line
			(start 0.120396 0.3048)
			(end 0.120396 0.2794)
			(stroke
				(width 0.1)
				(type default)
			)
			(layer "F.Fab")
		)
		(fp_line
			(start -0.12065 0.3048)
			(end -0.67945 0.3048)
			(stroke
				(width 0.1)
				(type default)
			)
			(layer "F.Fab")
		)
		(fp_line
			(start -0.67945 0.3048)
			(end -0.67945 -0.305054)
			(stroke
				(width 0.1)
				(type default)
			)
			(layer "F.Fab")
		)
		(pad "1" smd circle
			(at -0.40005 0 90)
			(size 0 0)
			(layers "F.Cu" "F.Mask" "F.Paste")
			(net "PVDD18_S5_P0_FB")
		)
		(pad "2" smd circle
			(at 0.40005 0 90)
			(size 0 0)
			(layers "F.Cu" "F.Mask" "F.Paste")
			(net "PVDD18_S5_P0_FB_RC")
		)
	)
	(footprint ""
		(layer "F.Cu")
		(at 285.75254 -403.961092 -90)
		(property "Reference" "R2625"
			(at 0 0 270)
			(layer "F.SilkS")
			(hide yes)
			(effects
				(font
					(size 1.27 1.27)
				)
			)
		)
		(property "Value" ""
			(at 0 0 270)
			(layer "F.Fab")
			(effects
				(font
					(size 1.27 1.27)
				)
			)
		)
		(duplicate_pad_numbers_are_jumpers no)
		(fp_line
			(start -0.7874 0.4064)
			(end -0.7874 -0.4064)
			(stroke
				(width 0.1524)
				(type default)
			)
			(layer "F.SilkS")
		)
		(fp_line
			(start 0.7874 0.4064)
			(end -0.7874 0.4064)
			(stroke
				(width 0.1524)
				(type default)
			)
			(layer "F.SilkS")
		)
		(fp_line
			(start -0.7874 -0.4064)
			(end 0.7874 -0.4064)
			(stroke
				(width 0.1524)
				(type default)
			)
			(layer "F.SilkS")
		)
		(fp_line
			(start 0.7874 -0.4064)
			(end 0.7874 0.4064)
			(stroke
				(width 0.1524)
				(type default)
			)
			(layer "F.SilkS")
		)
		(fp_line
			(start -0.67945 0.3048)
			(end -0.67945 -0.305054)
			(stroke
				(width 0.1)
				(type default)
			)
			(layer "F.Fab")
		)
		(fp_line
			(start -0.12065 0.3048)
			(end -0.67945 0.3048)
			(stroke
				(width 0.1)
				(type default)
			)
			(layer "F.Fab")
		)
		(fp_line
			(start 0.120396 0.3048)
			(end 0.120396 0.2794)
			(stroke
				(width 0.1)
				(type default)
			)
			(layer "F.Fab")
		)
		(fp_line
			(start 0.67945 0.3048)
			(end 0.120396 0.3048)
			(stroke
				(width 0.1)
				(type default)
			)
			(layer "F.Fab")
		)
		(fp_line
			(start -0.12065 0.2794)
			(end -0.12065 0.3048)
			(stroke
				(width 0.1)
				(type default)
			)
			(layer "F.Fab")
		)
		(fp_line
			(start 0.120396 0.2794)
			(end -0.12065 0.2794)
			(stroke
				(width 0.1)
				(type default)
			)
			(layer "F.Fab")
		)
		(fp_line
			(start -0.12065 -0.2794)
			(end 0.12065 -0.2794)
			(stroke
				(width 0.1)
				(type default)
			)
			(layer "F.Fab")
		)
		(fp_line
			(start 0.12065 -0.2794)
			(end 0.12065 -0.3048)
			(stroke
				(width 0.1)
				(type default)
			)
			(layer "F.Fab")
		)
		(fp_line
			(start 0.12065 -0.3048)
			(end 0.67945 -0.3048)
			(stroke
				(width 0.1)
				(type default)
			)
			(layer "F.Fab")
		)
		(fp_line
			(start 0.67945 -0.3048)
			(end 0.67945 0.3048)
			(stroke
				(width 0.1)
				(type default)
			)
			(layer "F.Fab")
		)
		(fp_line
			(start -0.67945 -0.305054)
			(end -0.12065 -0.305054)
			(stroke
				(width 0.1)
				(type default)
			)
			(layer "F.Fab")
		)
		(fp_line
			(start -0.12065 -0.305054)
			(end -0.12065 -0.2794)
			(stroke
				(width 0.1)
				(type default)
			)
			(layer "F.Fab")
		)
		(pad "1" smd circle
			(at -0.40005 0 270)
			(size 0 0)
			(layers "F.Cu" "F.Mask" "F.Paste")
			(net "P12V_HSC_TEMP_R")
		)
		(pad "2" smd circle
			(at 0.40005 0 270)
			(size 0 0)
			(layers "F.Cu" "F.Mask" "F.Paste")
			(net "P12V_HSC_TEMP_D+")
		)
	)
)
